# sdi-mipi-video-converter — KiCad custom design rules (.kicad_dru)
(version 1)

(rule "default_inner"
	(constraint track_width (opt 0.1mm))
	(constraint diff_pair_gap (opt 0.15mm))
	(condition "(A.NetClass == 'Default')")
	(layer inner)
)


(rule "ddr3_inner"
	(constraint track_width (max 0.162mm) (opt 0.162mm) (min 0.15mm))
	(constraint clearance (opt 0.6mm))
	(constraint diff_pair_gap (min 0.31mm) (opt 0.311mm) (max 0.312mm))
	(constraint diff_pair_uncoupled (max 2mm))
	(condition "(A.NetClass == '50Ohm-se_DDR3' || A.NetClass == '90Ohm-diff_DDR3')")
	(layer inner)
)

(rule "ddr3_outer"
	(constraint track_width (max 0.200mm) (opt 0.200mm) (min 0.150mm))
	(constraint diff_pair_gap (opt 0.196mm))
	(constraint clearance (opt 0.6mm))
	(constraint diff_pair_uncoupled (max 2mm))
	(condition "(A.NetClass == '50Ohm-se_DDR3' || A.NetClass == '90Ohm-diff_DDR3')")
	(layer outer)
)

(rule "CSI_outer"
	(constraint track_width (max 0.150mm) (opt 0.150mm) (min 0.150mm))
	(constraint diff_pair_gap (min 0.28mm) (opt 0.300mm) (max 0.320mm))
	(condition "A.NetClass == '100Ohm-diff_CSI'")
	(layer outer)
)

(rule "CSI_inner"
	(constraint track_width (max 0.168mm) (opt 0.168mm) (min 0.150mm))
	(constraint diff_pair_gap (min 0.28mm) (opt 0.300mm) (max 0.32mm))
	(condition "A.NetClass == '100Ohm-diff_CSI'")
	(layer inner)
)

(rule "SDI_D_outer"
	(constraint track_width (min 0.15mm) (opt 0.2mm) (max 0.2mm))
	(condition "A.NetClass == '50Ohm-se_SDI_D'")
	(layer outer)
)


(rule "SDI_D_inner"
	(constraint track_width (min 0.13mm) (opt 0.13mm) (max 0.13mm))
	(condition "A.NetClass == '50Ohm-se_SDI_D'")
	(layer inner)
)

(rule "SDI_D_length"
	(constraint skew (max 1.5mm))
	(condition "A.NetClass == '50Ohm-se_SDI_D'")
)

(rule "SDI"
	(constraint track_width (min 0.45mm) (opt 0.45mm) (max 0.45mm))
	(condition "A.NetClass == '75Ohm-se_SDI'")
)

(rule "SDI_diff"
	(constraint track_width (min 0.4mm) (opt 0.4mm) (max 0.4mm))
	(constraint diff_pair_gap (min 0.8mm) (opt 0.8mm) (max 0.8mm))
	(condition "A.NetClass == '140Ohm-diff_SDI'")
)

(rule "SDO"
	(constraint track_width (min 0.15mm) (opt 0.15mm) (max 0.15mm))
	(constraint diff_pair_gap (min 0.29mm) (opt 0.3mm) (max 0.31mm))
	(constraint diff_pair_uncoupled (max 2mm))
	(condition "A.NetClass == '100Ohm-diff_SDO'")
)
